# Bryce Canyon_Storage_Controller_Card_Stackup.xlsx — Stack up_16316-1 (pcb-stackup)
|  |  |  |  |  |  | Version |  |  |  |  |  |  |  |  |  |  |  |  |  |  |  |  |  |  |  |  |  |  |  |  |  |  |  |  |  |  |  |  |  |  |  |  |  |  |  |  |  |  |  |
| Board Number: |  | 16316-1 |  |  |  | 02 |  |  |  |  |  |  |  |  |  |  |  |  |  |  |  |  |  |  |  |  |  |  |  |  |  |  |  |  |  |  |  |  |  |  |  |  |  |  |  |  |  |  |  |
| Project name: |  | Bryce Canyon |  |  |  |  |  |  |  |  |  |  |  |  |  |  |  |  |  |  |  |  |  |  |  |  |  |  |  |  |  |  |  |  |  |  |  |  |  |  |  |  |  |  |  |  |  |  |  |
| Model Name: |  | Storage Controller Card |  |  |  |  |  |  |  |  |  |  |  |  |  |  |  |  |  |  |  |  |  |  |  |  |  |  |  |  |  |  |  |  |  |  |  |  |  |  |  |  |  |  |  |  |  |  |  |
| Layer Count: |  | 8 Layer |  |  |  |  |  |  |  |  |  |  |  |  |  |  |  |  |  |  |  |  |  |  |  |  |  |  |  |  |  |  |  |  |  |  |  |  |  |  |  |  |  |  |  |  |  |  |  |
| Date: |  | 2017-09-25 00:00:00 |  |  |  |  |  |  |  |  |  |  |  |  |  |  |  |  |  |  |  |  |  |  |  |  |  |  |  |  |  |  |  |  |  |  |  |  |  |  |  |  |  |  |  |  |  |  |  |
| Low Loss Material: |  | TU863+VLP (Tg : 180/Td : 370) |  |  |  |  |  |  | Single Ended Type(mil) |  |  |  |  | Differential Type(mil) |  |  |  |  |  |  |  |  |  |  |  |  |  |  |  |  |  |  |  |  |  |  |  |  |  |  |  |  |  |  |  |  |  |  |  |
| Gold Finger(Y/N): |  | N |  |  |  |  |  | Imp | 50 |  |  |  | Imp | 85 |  |  |  |  |  | 100 |  |  |  |  |  | 97 |  |  |  |  |  | 88 |  |  |  |  |  | 92 |  |  |  |  |  | 83 |  |  |  |  |  |
| Customer: |  | <name> |  |  |  |  |  | Variation | Inner/Outer+/-5ohm |  |  |  | Variation | Inner/Outer+/-10% |  |  |  |  |  | Inner/Outer+/-10% |  |  |  |  |  | Outer+/-10% |  |  |  |  |  | Inner+/-10% |  |  |  |  |  | Outer+/-10% |  |  |  |  |  | Inner+/-10% |  |  |  |  |  |
| EE engineer |  | <name> |  |  |  |  |  | Bus | MISC./I2C |  |  |  | Bus | PCIe/Clock/USB |  |  |  |  |  | Clock/SATA |  |  |  |  |  | BGA Break out(SAS.SATA) |  |  |  |  |  | BGA Break out(SAS.SATA) |  |  |  |  |  | BGA Break out(PCIE) |  |  |  |  |  | BGA Break out(PCIE) |  |  |  |  |  |
| SI Engineer |  | <name> |  |  |  |  |  |  |  |  |  |  |  |  |  |  |  |  |  |  |  |  |  |  |  |  |  |  |  |  |  |  |  |  |  |  |  |  |  |  |  |  |  |  |  |  |  |  |  |
|  |  |  |  |  |  |  |  | Type | SE |  |  |  | Type | DP |  |  |  |  |  | DP |  |  |  |  |  | DP |  |  |  |  |  | DP |  |  |  |  |  | DP |  |  |  |  |  | DP |  |  |  |  |  |
| Layer |  |  | Thickness |  | Glass/Copper Style | Er | Df(1G) | Layers | 1,3,6,8 |  |  |  | Layers | 1,3,6,8 |  |  |  |  |  | 1,3,6,8 |  |  |  |  |  | 1,8 |  |  |  |  |  | 3,6 |  |  |  |  |  | 1,8 |  |  |  |  |  | 3,6 |  |  |  |  |  |
|  |  | Cu oz | Wiwynn |  |  | Wiwynn |  |  | Wiwynn |  |  |  |  | Wiwynn |  |  |  |  |  | Wiwynn |  |  |  |  |  | Wiwynn |  |  |  |  |  | Wiwynn |  |  |  |  |  | Wiwynn |  |  |  |  |  | Wiwynn |  |  |  |  |  |
|  | Mask |  | 0.5 |  |  | 3.4 | 0.025 |  | Width | Imp | Width | Imp |  | Width | Space | Imp | Width | Space | Imp | Width | Space | Imp | Width | Space | Imp | Width | Space | Imp | Width | Space | Imp | Width | Space | Imp | Width | Space | Imp | Width | Space | Imp | Width | Space | Imp | Width | Space | Imp | Width | Space | Imp |
| Top | Signal | 3/8 oz+plating | 1.7 |  |  |  |  | S1 | 5(L2) | 50.08 |  |  | S1 | 5.75(L2) | 6.5 | 85.36 |  |  |  | 4.9(L2) | 11.1 | 96.82 |  |  |  | 3.5(L2) | 4 |  |  |  |  |  |  |  |  |  |  | 3.75(L2) | 3.5 |  |  |  |  |  |  |  |  |  |  |
|  | Prepreg |  | 3 |  |  | 3.9 | 0.006 |  |  |  |  |  |  |  |  |  |  |  |  |  |  |  |  |  |  |  |  |  |  |  |  |  |  |  |  |  |  |  |  |  |  |  |  |  |  |  |  |  |  |
| L2 | GND | 1 oz | 1.3 |  |  |  |  | P2 | reference layer |  |  |  | P2 | reference layer |  |  |  |  |  | reference layer |  |  |  |  |  | reference layer |  |  |  |  |  | reference layer |  |  |  |  |  | reference layer |  |  |  |  |  | reference layer |  |  |  |  |  |
|  | Core |  | 4 |  |  | 3.9 | 0.006 |  |  |  |  |  |  |  |  |  |  |  |  |  |  |  |  |  |  |  |  |  |  |  |  |  |  |  |  |  |  |  |  |  |  |  |  |  |  |  |  |  |  |
| L3 | Signal | 1 oz | 1.3 |  |  |  |  | S3 | 5(L2/L4) | 49.28 |  |  | S3 | 5.5(L2/L4) | 7.5 | 84.9 |  |  |  | 4(L2/L4) | 8 | 97.59 |  |  |  |  |  |  |  |  |  | 3.5(L2/L4) | 4 |  |  |  |  |  |  |  |  |  |  | 3.75(L2/L4) | 3.5 |  |  |  |  |
|  | Prepreg |  | 16.4 |  |  | 4.2 | 0.006 |  |  |  |  |  |  |  |  |  |  |  |  |  |  |  |  |  |  |  |  |  |  |  |  |  |  |  |  |  |  |  |  |  |  |  |  |  |  |  |  |  |  |
| L4 | POWER | 1 oz | 1.3 |  |  |  |  | P4 | reference layer |  |  |  | P4 | reference layer |  |  |  |  |  | reference layer |  |  |  |  |  | reference layer |  |  |  |  |  | reference layer |  |  |  |  |  | reference layer |  |  |  |  |  | reference layer |  |  |  |  |  |
|  | Core |  | 4 |  |  | 3.8 | 0.006 |  |  |  |  |  |  |  |  |  |  |  |  |  |  |  |  |  |  |  |  |  |  |  |  |  |  |  |  |  |  |  |  |  |  |  |  |  |  |  |  |  |  |
| L5 | POWER | 1 oz | 1.3 | 0 | 0 |  |  | P5 | reference layer |  |  |  | P5 | reference layer |  |  |  |  |  | reference layer |  |  |  |  |  | reference layer |  |  |  |  |  | reference layer |  |  |  |  |  | reference layer |  |  |  |  |  | reference layer |  |  |  |  |  |
|  | Prepreg |  | 16.4 | 0 | 0 | 4.2 | 0.006 |  |  |  |  |  |  |  |  |  |  |  |  |  |  |  |  |  |  |  |  |  |  |  |  |  |  |  |  |  |  |  |  |  |  |  |  |  |  |  |  |  |  |
| L6 | Signal | 1 oz | 1.3 | 0 | 0 |  |  | S6 | 5(L5/L7) | 49.28 |  |  | S6 | 5.5(L5/L7) | 7.5 | 84.9 |  |  |  | 4(L5/L7) | 8 | 97.59 |  |  |  |  |  |  |  |  |  | 3.5(L5/L7) | 4 |  |  |  |  |  |  |  |  |  |  | 3.75(L5/L7) | 3.5 |  |  |  |  |
|  | Core |  | 4 | 0 | 0 | 3.9 | 0.006 |  |  |  |  |  |  |  |  |  |  |  |  |  |  |  |  |  |  |  |  |  |  |  |  |  |  |  |  |  |  |  |  |  |  |  |  |  |  |  |  |  |  |
| L7 | GND | 1 oz | 1.3 | 0 | 0 |  |  | P7 | reference layer |  |  |  | P7 | reference layer |  |  |  |  |  | reference layer |  |  |  |  |  | reference layer |  |  |  |  |  | reference layer |  |  |  |  |  | reference layer |  |  |  |  |  | reference layer |  |  |  |  |  |
|  | Prepreg |  | 3 | 0 | 0 | 3.9 | 0.006 |  |  |  |  |  |  |  |  |  |  |  |  |  |  |  |  |  |  |  |  |  |  |  |  |  |  |  |  |  |  |  |  |  |  |  |  |  |  |  |  |  |  |
| Bottom | Signal | 3/8 oz+plating | 1.7 | 0 | 0 |  |  | S8 | 5(L7) | 50.08 |  |  | S8 | 5.75(L7) | 6.5 | 85.36 |  |  |  | 4.9(L7) | 11.1 | 96.82 |  |  |  | 3.5(L7) | 4 |  |  |  |  |  |  |  |  |  |  | 3.75(L7) | 3.5 |  |  |  |  |  |  |  |  |  |  |
|  | Mask |  | 0.5 | 0 |  | 3.4 | 0.025 |  |  |  |  |  |  |  |  |  |  |  |  |  |  |  |  |  |  |  |  |  |  |  |  |  |  |  |  |  |  |  |  |  |  |  |  |  |  |  |  |  |  |
| Thickness requirement: 1.6 ± 10% mm |  | mil | 62.99999999999999 |  |  |  |  |  |  |  |  |  |  |  |  |  |  |  |  |  |  |  |  |  |  |  |  |  |  |  |  |  |  |  |  |  |  |  |  |  |  |  |  |  |  |  |  |  |  |
|  |  | mm | 1.6002032004064006 |  |  |  |  |  |  |  |  |  |  |  |  |  |  |  |  |  |  |  |  |  |  |  |  |  |  |  |  |  |  |  |  |  |  |  |  |  |  |  |  |  |  |  |  |  |  |
| Note: | 1. Unit is mil |  |  |  |  |  |  |  |  |  |  |  |  |  |  |  |  |  |  |  |  |  |  |  |  |  |  |  |  |  |  |  |  |  |  |  |  |  |  |  |  |  |  |  |  |  |  |  |  |
|  | 2. The total thickness includes trace and solder mask. |  |  |  |  |  |  |  |  |  |  |  |  |  |  |  |  |  |  |  |  |  |  |  |  |  |  |  |  |  |  |  |  |  |  |  |  |  |  |  |  |  |  |  |  |  |  |  |  |
|  | 3. Minimum hole copper thickness is 1.0 mil. |  |  |  |  |  |  |  |  |  |  |  |  |  |  |  |  |  |  |  |  |  |  |  |  |  |  |  |  |  |  |  |  |  |  |  |  |  |  |  |  |  |  |  |  |  |  |  |  |
|  | 4. Minimum surface copper thickness 1.5 mil. |  |  |  |  |  |  |  |  |  |  |  |  |  |  |  |  |  |  |  |  |  |  |  |  |  |  |  |  |  |  |  |  |  |  |  |  |  |  |  |  |  |  |  |  |  |  |  |  |
|  | 5. If there is no controlled impedance line described as the stackup in the gerber file, PCB supplier can ignore this kind of impedance control directly, but need to inform Wiwynn in engineering question(EQ). |  |  |  |  |  |  |  |  |  |  |  |  |  |  |  |  |  |  |  |  |  |  |  |  |  |  |  |  |  |  |  |  |  |  |  |  |  |  |  |  |  |  |  |  |  |  |  |  |
|  | 6. PCB test coupon requirement and PCB test note are described in the another sheets. |  |  |  |  |  |  |  |  |  |  |  |  |  |  |  |  |  |  |  |  |  |  |  |  |  |  |  |  |  |  |  |  |  |  |  |  |  |  |  |  |  |  |  |  |  |  |  |  |
|  | 7. If there is no "Delta-L" design in gerber file, PCB supplier should design 85 ohm "Delta-L" angle routing coupon and provide the measurement results in FAI report which meet the following criteria: |  |  |  |  |  |  |  |  |  |  |  |  |  |  |  |  |  |  |  |  |  |  |  |  |  |  |  |  |  |  |  |  |  |  |  |  |  |  |  |  |  |  |  |  |  |  |  |  |
|  | For low-loss material |  |  |  |  |  |  |  |  |  |  |  |  |  |  |  |  |  |  |  |  |  |  |  |  |  |  |  |  |  |  |  |  |  |  |  |  |  |  |  |  |  |  |  |  |  |  |  |  |
|  | (1)   0.55 dB/inch @ 4GHz; 1.05 dB/inch @ 8GHz for microstrip routing |  |  |  |  |  |  |  |  |  |  |  |  |  |  |  |  |  |  |  |  |  |  |  |  |  |  |  |  |  |  |  |  |  |  |  |  |  |  |  |  |  |  |  |  |  |  |  |  |
|  | (2)   0.48 dB/inch @ 4GHz; 0.9 dB/inch @ 8GHz for stripline routing |  |  |  |  |  |  |  |  |  |  |  |  |  |  |  |  |  |  |  |  |  |  |  |  |  |  |  |  |  |  |  |  |  |  |  |  |  |  |  |  |  |  |  |  |  |  |  |  |
